# SCM (Grand Teton) — schematic netlist excerpt (pin names and nets, part order shuffled) for the footprints in the layout excerpt that follows; sources: Cadence DE-HDL packaged netlist, KiCad conversion of 12092022_DA0F0TMDCD0_F0T_Management_Board_D_brd_V3_OCP.brd

R321  Q_RES  0 5% CHIP  pkg 0402LF  page 36 : A = PWRGD_P1V8_AUX_R1 ; B = PWRGD_P1V8_AUX
R885  Q_RES  4.7K 1% CHIP  pkg 0402LF  page 14 : A = P1V8_AUX ; B = AC_PWR_BMC_BTN_N

(kicad_pcb
	(version 20260206)
	(generator "pcbnew")
	(generator_version "10.0")
	(general
		(thickness 1.6)
		(legacy_teardrops no)
	)
	(paper "A4")
	(title_block
		(title "12092022_DA0F0TMDCD0_F0T_Management_Board_D_brd_V3_OCP.brd")
		(comment 1 "Grand Teton / footprints 1409-1410 of 1440")
	)
	(layers
		(0 "F.Cu" signal "TOP")
		(4 "In1.Cu" signal "GND")
		(6 "In2.Cu" signal "IN1")
		(8 "In3.Cu" signal "GND1")
		(10 "In4.Cu" signal "IN2")
		(12 "In5.Cu" signal "VCC")
		(14 "In6.Cu" signal "VCC1")
		(16 "In7.Cu" signal "IN3")
		(18 "In8.Cu" signal "GND2")
		(20 "In9.Cu" signal "IN4")
		(22 "In10.Cu" signal "GND3")
		(2 "B.Cu" signal "BOTTOM")
		(9 "F.Adhes" user "F.Adhesive")
		(11 "B.Adhes" user "B.Adhesive")
		(13 "F.Paste" user "Package Geometry/Pastemask Top")
		(15 "B.Paste" user "Package Geometry/Pastemask Bottom")
		(5 "F.SilkS" user "Ref Des/Silkscreen Top")
		(7 "B.SilkS" user "Ref Des/Silkscreen Bottom")
		(1 "F.Mask" user "Board Geometry/Soldermask Top")
		(3 "B.Mask" user "Board Geometry/Soldermask Bottom")
		(17 "Dwgs.User" user "User.Drawings")
		(19 "Cmts.User" user "User.Comments")
		(21 "Eco1.User" user "User.Eco1")
		(23 "Eco2.User" user "User.Eco2")
		(25 "Edge.Cuts" user "Board Geometry/Outline")
		(27 "Margin" user)
		(31 "F.CrtYd" user "Package Geometry/Place Bound Top")
		(29 "B.CrtYd" user "Package Geometry/Place Bound Bottom")
		(35 "F.Fab" user "Ref Des/Assembly Top")
		(33 "B.Fab" user "Ref Des/Assembly Bottom")
	)
	(footprint ""
		(layer "B.Cu")
		(at 19.939 -101.981 -90)
		(property "Reference" "R321"
			(at 0 0 90)
			(layer "B.SilkS")
			(hide yes)
			(effects
				(font
					(size 1.27 1.27)
				)
				(justify mirror)
			)
		)
		(property "Value" ""
			(at 0 0 90)
			(layer "B.Fab")
			(effects
				(font
					(size 1.27 1.27)
				)
				(justify mirror)
			)
		)
		(duplicate_pad_numbers_are_jumpers no)
		(fp_line
			(start -0.7874 0.4064)
			(end 0.7874 0.4064)
			(stroke
				(width 0.1524)
				(type default)
			)
			(layer "B.SilkS")
		)
		(fp_line
			(start 0.7874 0.4064)
			(end 0.7874 -0.4064)
			(stroke
				(width 0.1524)
				(type default)
			)
			(layer "B.SilkS")
		)
		(fp_line
			(start -0.7874 -0.4064)
			(end -0.7874 0.4064)
			(stroke
				(width 0.1524)
				(type default)
			)
			(layer "B.SilkS")
		)
		(fp_line
			(start 0.7874 -0.4064)
			(end -0.7874 -0.4064)
			(stroke
				(width 0.1524)
				(type default)
			)
			(layer "B.SilkS")
		)
		(fp_line
			(start -0.67945 0.3048)
			(end -0.120396 0.3048)
			(stroke
				(width 0.1)
				(type default)
			)
			(layer "B.Fab")
		)
		(fp_line
			(start -0.120396 0.3048)
			(end -0.120396 0.2794)
			(stroke
				(width 0.1)
				(type default)
			)
			(layer "B.Fab")
		)
		(fp_line
			(start 0.12065 0.3048)
			(end 0.67945 0.3048)
			(stroke
				(width 0.1)
				(type default)
			)
			(layer "B.Fab")
		)
		(fp_line
			(start 0.67945 0.3048)
			(end 0.67945 -0.305054)
			(stroke
				(width 0.1)
				(type default)
			)
			(layer "B.Fab")
		)
		(fp_line
			(start -0.120396 0.2794)
			(end 0.12065 0.2794)
			(stroke
				(width 0.1)
				(type default)
			)
			(layer "B.Fab")
		)
		(fp_line
			(start 0.12065 0.2794)
			(end 0.12065 0.3048)
			(stroke
				(width 0.1)
				(type default)
			)
			(layer "B.Fab")
		)
		(fp_line
			(start -0.12065 -0.2794)
			(end -0.12065 -0.3048)
			(stroke
				(width 0.1)
				(type default)
			)
			(layer "B.Fab")
		)
		(fp_line
			(start 0.12065 -0.2794)
			(end -0.12065 -0.2794)
			(stroke
				(width 0.1)
				(type default)
			)
			(layer "B.Fab")
		)
		(fp_line
			(start -0.67945 -0.3048)
			(end -0.67945 0.3048)
			(stroke
				(width 0.1)
				(type default)
			)
			(layer "B.Fab")
		)
		(fp_line
			(start -0.12065 -0.3048)
			(end -0.67945 -0.3048)
			(stroke
				(width 0.1)
				(type default)
			)
			(layer "B.Fab")
		)
		(fp_line
			(start 0.12065 -0.305054)
			(end 0.12065 -0.2794)
			(stroke
				(width 0.1)
				(type default)
			)
			(layer "B.Fab")
		)
		(fp_line
			(start 0.67945 -0.305054)
			(end 0.12065 -0.305054)
			(stroke
				(width 0.1)
				(type default)
			)
			(layer "B.Fab")
		)
		(pad "1" smd circle
			(at 0.40005 0 90)
			(size 0 0)
			(layers "B.Cu" "B.Mask" "B.Paste")
			(net "PWRGD_P1V8_AUX_R1")
		)
		(pad "2" smd circle
			(at -0.40005 0 90)
			(size 0 0)
			(layers "B.Cu" "B.Mask" "B.Paste")
			(net "PWRGD_P1V8_AUX")
		)
	)
	(footprint ""
		(layer "B.Cu")
		(at 66.802 -12.446 180)
		(property "Reference" "R885"
			(at 0 0 0)
			(layer "B.SilkS")
			(hide yes)
			(effects
				(font
					(size 1.27 1.27)
				)
				(justify mirror)
			)
		)
		(property "Value" ""
			(at 0 0 0)
			(layer "B.Fab")
			(effects
				(font
					(size 1.27 1.27)
				)
				(justify mirror)
			)
		)
		(duplicate_pad_numbers_are_jumpers no)
		(fp_line
			(start 0.7874 0.4064)
			(end 0.7874 -0.4064)
			(stroke
				(width 0.1524)
				(type default)
			)
			(layer "B.SilkS")
		)
		(fp_line
			(start 0.7874 -0.4064)
			(end -0.7874 -0.4064)
			(stroke
				(width 0.1524)
				(type default)
			)
			(layer "B.SilkS")
		)
		(fp_line
			(start -0.7874 0.4064)
			(end 0.7874 0.4064)
			(stroke
				(width 0.1524)
				(type default)
			)
			(layer "B.SilkS")
		)
		(fp_line
			(start -0.7874 -0.4064)
			(end -0.7874 0.4064)
			(stroke
				(width 0.1524)
				(type default)
			)
			(layer "B.SilkS")
		)
		(fp_line
			(start 0.67945 0.3048)
			(end 0.67945 -0.305054)
			(stroke
				(width 0.1)
				(type default)
			)
			(layer "B.Fab")
		)
		(fp_line
			(start 0.67945 -0.305054)
			(end 0.12065 -0.305054)
			(stroke
				(width 0.1)
				(type default)
			)
			(layer "B.Fab")
		)
		(fp_line
			(start 0.12065 0.3048)
			(end 0.67945 0.3048)
			(stroke
				(width 0.1)
				(type default)
			)
			(layer "B.Fab")
		)
		(fp_line
			(start 0.12065 0.2794)
			(end 0.12065 0.3048)
			(stroke
				(width 0.1)
				(type default)
			)
			(layer "B.Fab")
		)
		(fp_line
			(start 0.12065 -0.2794)
			(end -0.12065 -0.2794)
			(stroke
				(width 0.1)
				(type default)
			)
			(layer "B.Fab")
		)
		(fp_line
			(start 0.12065 -0.305054)
			(end 0.12065 -0.2794)
			(stroke
				(width 0.1)
				(type default)
			)
			(layer "B.Fab")
		)
		(fp_line
			(start -0.120396 0.3048)
			(end -0.120396 0.2794)
			(stroke
				(width 0.1)
				(type default)
			)
			(layer "B.Fab")
		)
		(fp_line
			(start -0.120396 0.2794)
			(end 0.12065 0.2794)
			(stroke
				(width 0.1)
				(type default)
			)
			(layer "B.Fab")
		)
		(fp_line
			(start -0.12065 -0.2794)
			(end -0.12065 -0.3048)
			(stroke
				(width 0.1)
				(type default)
			)
			(layer "B.Fab")
		)
		(fp_line
			(start -0.12065 -0.3048)
			(end -0.67945 -0.3048)
			(stroke
				(width 0.1)
				(type default)
			)
			(layer "B.Fab")
		)
		(fp_line
			(start -0.67945 0.3048)
			(end -0.120396 0.3048)
			(stroke
				(width 0.1)
				(type default)
			)
			(layer "B.Fab")
		)
		(fp_line
			(start -0.67945 -0.3048)
			(end -0.67945 0.3048)
			(stroke
				(width 0.1)
				(type default)
			)
			(layer "B.Fab")
		)
		(pad "1" smd circle
			(at 0.40005 0)
			(size 0 0)
			(layers "B.Cu" "B.Mask" "B.Paste")
			(net "P1V8_AUX")
		)
		(pad "2" smd circle
			(at -0.40005 0)
			(size 0 0)
			(layers "B.Cu" "B.Mask" "B.Paste")
			(net "AC_PWR_BMC_BTN_N")
		)
	)
)
